# BASEBOARD_FAB2 (Tioga Pass) — schematic netlist excerpt (pin names and nets, part order shuffled) for the footprints in the layout excerpt that follows; sources: Cadence DE-HDL packaged netlist, KiCad conversion of Wiwynn_Tioga_Pass_MB.brd

C5P21  CAP  100UF 4V 20% X5R  pkg 0805  page 42 : A = PVCCMCP_CPU0 ; B = GND
C8T2  CAP_A  47UF 4V 20% X5R  pkg 0603V  page 225 : A = PVDDQ_GHJ ; B = GND
C5G49  CAP_A  22.0UF 4V 20% X6S  pkg 0603V  page 242 : A = PVDDQ_ABC ; B = GND

(kicad_pcb
	(version 20260206)
	(generator "pcbnew")
	(generator_version "10.0")
	(general
		(thickness 1.6)
		(legacy_teardrops no)
	)
	(paper "A4")
	(title_block
		(title "Wiwynn_Tioga_Pass_MB.brd")
		(comment 1 "Tioga Pass / footprints 2718-2720 of 4770")
	)
	(layers
		(0 "F.Cu" signal "TOP")
		(4 "In1.Cu" signal "L2GND")
		(6 "In2.Cu" signal "L3")
		(8 "In3.Cu" signal "L4GND")
		(10 "In4.Cu" signal "L5")
		(12 "In5.Cu" signal "L6GND")
		(14 "In6.Cu" signal "L7VCC")
		(16 "In7.Cu" signal "L8VCC")
		(18 "In8.Cu" signal "L9GND")
		(20 "In9.Cu" signal "L10")
		(22 "In10.Cu" signal "L11GND")
		(24 "In11.Cu" signal "L12")
		(26 "In12.Cu" signal "L13GND")
		(2 "B.Cu" signal "BOTTOM")
		(9 "F.Adhes" user "F.Adhesive")
		(11 "B.Adhes" user "B.Adhesive")
		(13 "F.Paste" user "Package Geometry/Pastemask Top")
		(15 "B.Paste" user "Package Geometry/Pastemask Bottom")
		(5 "F.SilkS" user "Ref Des/Silkscreen Top")
		(7 "B.SilkS" user "Ref Des/Silkscreen Bottom")
		(1 "F.Mask" user "Board Geometry/Soldermask Top")
		(3 "B.Mask" user "Board Geometry/Soldermask Bottom")
		(17 "Dwgs.User" user "User.Drawings")
		(19 "Cmts.User" user "User.Comments")
		(21 "Eco1.User" user "User.Eco1")
		(23 "Eco2.User" user "User.Eco2")
		(25 "Edge.Cuts" user "Board Geometry/Outline")
		(27 "Margin" user)
		(31 "F.CrtYd" user "Package Geometry/Place Bound Top")
		(29 "B.CrtYd" user "Package Geometry/Place Bound Bottom")
		(35 "F.Fab" user "Ref Des/Assembly Top")
		(33 "B.Fab" user "Ref Des/Assembly Bottom")
	)
	(footprint ""
		(layer "B.Cu")
		(at 269.521686 -77.82814)
		(property "Reference" "C5P21"
			(at 0 0 0)
			(layer "B.SilkS")
			(hide yes)
			(effects
				(font
					(size 1.27 1.27)
				)
				(justify mirror)
			)
		)
		(property "Value" ""
			(at 0 0 0)
			(layer "B.Fab")
			(effects
				(font
					(size 1.27 1.27)
				)
				(justify mirror)
			)
		)
		(duplicate_pad_numbers_are_jumpers no)
		(fp_poly
			(pts
				(xy 0.7239 -0.2159) (xy -0.7239 -0.2159) (xy -0.7239 1.9939) (xy 0.7239 1.9939)
			)
			(stroke
				(width 0)
				(type default)
			)
			(fill no)
			(layer "B.CrtYd")
		)
		(fp_line
			(start -0.7239 -0.2159)
			(end 0.7239 -0.2159)
			(stroke
				(width 0.1)
				(type default)
			)
			(layer "B.Fab")
		)
		(fp_line
			(start -0.7239 1.9939)
			(end -0.7239 -0.2159)
			(stroke
				(width 0.1)
				(type default)
			)
			(layer "B.Fab")
		)
		(fp_line
			(start 0.7239 -0.2159)
			(end 0.7239 1.9939)
			(stroke
				(width 0.1)
				(type default)
			)
			(layer "B.Fab")
		)
		(fp_line
			(start 0.7239 1.9939)
			(end -0.7239 1.9939)
			(stroke
				(width 0.1)
				(type default)
			)
			(layer "B.Fab")
		)
		(pad "1" smd rect
			(at 0 0 180)
			(size 1.27 1.016)
			(layers "B.Cu" "B.Mask" "B.Paste")
			(net "PVCCMCP_CPU0")
		)
		(pad "2" smd rect
			(at 0 1.778 180)
			(size 1.27 1.016)
			(layers "B.Cu" "B.Mask" "B.Paste")
			(net "GND")
		)
		(zone
			(layer "B.Cu")
			(hatch none 0.5)
			(connect_pads
				(clearance 0)
			)
			(min_thickness 0.25)
			(keepout
				(tracks not_allowed)
				(vias allowed)
				(pads allowed)
				(copperpour not_allowed)
				(footprints allowed)
			)
			(placement
				(enabled no)
				(sheetname "")
			)
			(fill
				(thermal_gap 0.5)
				(thermal_bridge_width 0.5)
				(island_removal_mode 0)
			)
			(polygon
				(pts
					(xy 270.156686 -77.32014) (xy 268.886686 -77.32014) (xy 268.886686 -76.55814) (xy 270.156686 -76.55814)
				)
			)
		)
	)
	(footprint ""
		(layer "B.Cu")
		(at 276.000464 -12.954 90)
		(property "Reference" "C5G49"
			(at -1.14681 0.76708 180)
			(unlocked yes)
			(layer "B.SilkS")
			(effects
				(font
					(size 0.7874 0.5842)
					(thickness 0.1524)
				)
				(justify mirror)
			)
		)
		(property "Value" ""
			(at 0 0 90)
			(layer "B.Fab")
			(effects
				(font
					(size 1.27 1.27)
				)
				(justify mirror)
			)
		)
		(duplicate_pad_numbers_are_jumpers no)
		(fp_rect
			(start -0.4953 -0.2032)
			(end 0.4953 1.6002)
			(stroke
				(width 0)
				(type default)
			)
			(fill no)
			(layer "B.CrtYd")
		)
		(fp_line
			(start 0.4953 -0.2032)
			(end -0.4953 -0.2032)
			(stroke
				(width 0.1)
				(type default)
			)
			(layer "B.Fab")
		)
		(fp_line
			(start -0.4953 -0.2032)
			(end -0.4953 1.6002)
			(stroke
				(width 0.1)
				(type default)
			)
			(layer "B.Fab")
		)
		(fp_line
			(start 0.4953 1.6002)
			(end 0.4953 -0.2032)
			(stroke
				(width 0.1)
				(type default)
			)
			(layer "B.Fab")
		)
		(fp_line
			(start -0.4953 1.6002)
			(end 0.4953 1.6002)
			(stroke
				(width 0.1)
				(type default)
			)
			(layer "B.Fab")
		)
		(pad "1" smd rect
			(at 0 0 270)
			(size 0.762 0.889)
			(layers "B.Cu" "B.Mask" "B.Paste")
			(net "PVDDQ_ABC")
		)
		(pad "2" smd rect
			(at 0 1.397 270)
			(size 0.762 0.889)
			(layers "B.Cu" "B.Mask" "B.Paste")
			(net "GND")
		)
		(zone
			(layer "B.Cu")
			(hatch none 0.5)
			(connect_pads
				(clearance 0)
			)
			(min_thickness 0.25)
			(keepout
				(tracks not_allowed)
				(vias allowed)
				(pads allowed)
				(copperpour not_allowed)
				(footprints allowed)
			)
			(placement
				(enabled no)
				(sheetname "")
			)
			(fill
				(thermal_gap 0.5)
				(thermal_bridge_width 0.5)
				(island_removal_mode 0)
			)
			(polygon
				(pts
					(xy 276.444964 -12.573) (xy 276.952964 -12.573) (xy 276.952964 -13.335) (xy 276.444964 -13.335)
				)
			)
		)
	)
	(footprint ""
		(layer "B.Cu")
		(at 80.719168 -27.2034 90)
		(property "Reference" "C8T2"
			(at 0.96393 5.132832 0)
			(unlocked yes)
			(layer "B.SilkS")
			(effects
				(font
					(size 0.7874 0.5842)
					(thickness 0.1524)
				)
				(justify mirror)
			)
		)
		(property "Value" ""
			(at 0 0 90)
			(layer "B.Fab")
			(effects
				(font
					(size 1.27 1.27)
				)
				(justify mirror)
			)
		)
		(duplicate_pad_numbers_are_jumpers no)
		(fp_rect
			(start 0.500126 1.598422)
			(end -0.500126 -0.201422)
			(stroke
				(width 0)
				(type default)
			)
			(fill no)
			(layer "B.CrtYd")
		)
		(fp_line
			(start 0.500126 -0.201422)
			(end -0.500126 -0.201422)
			(stroke
				(width 0.1)
				(type default)
			)
			(layer "B.Fab")
		)
		(fp_line
			(start -0.500126 -0.201422)
			(end -0.500126 1.598422)
			(stroke
				(width 0.1)
				(type default)
			)
			(layer "B.Fab")
		)
		(fp_line
			(start 0.500126 1.598422)
			(end 0.500126 -0.201422)
			(stroke
				(width 0.1)
				(type default)
			)
			(layer "B.Fab")
		)
		(fp_line
			(start -0.500126 1.598422)
			(end 0.500126 1.598422)
			(stroke
				(width 0.1)
				(type default)
			)
			(layer "B.Fab")
		)
		(pad "1" smd rect
			(at 0 0)
			(size 0.889 0.9906)
			(layers "B.Cu" "B.Mask" "B.Paste")
			(net "PVDDQ_GHJ")
		)
		(pad "2" smd rect
			(at 0 1.397)
			(size 0.889 0.9906)
			(layers "B.Cu" "B.Mask" "B.Paste")
			(net "GND")
		)
		(zone
			(layer "B.Cu")
			(hatch none 0.5)
			(connect_pads
				(clearance 0)
			)
			(min_thickness 0.25)
			(keepout
				(tracks allowed)
				(vias not_allowed)
				(pads allowed)
				(copperpour not_allowed)
				(footprints allowed)
			)
			(placement
				(enabled no)
				(sheetname "")
			)
			(fill
				(thermal_gap 0.5)
				(thermal_bridge_width 0.5)
				(island_removal_mode 0)
			)
			(polygon
				(pts
					(xy 81.671668 -27.6987) (xy 81.163668 -27.6987) (xy 81.163668 -26.7081) (xy 81.671668 -26.7081)
				)
			)
		)
		(zone
			(layer "B.Cu")
			(hatch none 0.5)
			(connect_pads
				(clearance 0)
			)
			(min_thickness 0.25)
			(keepout
				(tracks not_allowed)
				(vias allowed)
				(pads allowed)
				(copperpour not_allowed)
				(footprints allowed)
			)
			(placement
				(enabled no)
				(sheetname "")
			)
			(fill
				(thermal_gap 0.5)
				(thermal_bridge_width 0.5)
				(island_removal_mode 0)
			)
			(polygon
				(pts
					(xy 81.671668 -27.6987) (xy 81.163668 -27.6987) (xy 81.163668 -26.7081) (xy 81.671668 -26.7081)
				)
			)
		)
	)
)
